(kicad_pcb
	(version 20260206)
	(generator "pcbnew")
	(generator_version "10.0")
	(general
		(thickness 1.6)
		(legacy_teardrops no)
	)
	(paper "A4")
	(title_block
		(title "Bryce Canyon_F.DPB_16315-1-OCP.brd")
		(comment 1 "Bryce Canyon / footprints 1699-1705 of 2223")
	)
	(layers
		(0 "F.Cu" signal "TOP")
		(4 "In1.Cu" signal "L2GND")
		(6 "In2.Cu" signal "L3")
		(8 "In3.Cu" signal "L4GND")
		(10 "In4.Cu" signal "L5")
		(12 "In5.Cu" signal "L6VCC")
		(14 "In6.Cu" signal "L7VCC")
		(16 "In7.Cu" signal "L8")
		(18 "In8.Cu" signal "L9GND")
		(20 "In9.Cu" signal "L10")
		(22 "In10.Cu" signal "L11GND")
		(2 "B.Cu" signal "BOTTOM")
		(9 "F.Adhes" user "F.Adhesive")
		(11 "B.Adhes" user "B.Adhesive")
		(13 "F.Paste" user "Package Geometry/Pastemask Top")
		(15 "B.Paste" user "Package Geometry/Pastemask Bottom")
		(5 "F.SilkS" user "Ref Des/Silkscreen Top")
		(7 "B.SilkS" user "Ref Des/Silkscreen Bottom")
		(1 "F.Mask" user "Board Geometry/Soldermask Top")
		(3 "B.Mask" user "Board Geometry/Soldermask Bottom")
		(17 "Dwgs.User" user "User.Drawings")
		(19 "Cmts.User" user "User.Comments")
		(21 "Eco1.User" user "User.Eco1")
		(23 "Eco2.User" user "User.Eco2")
		(25 "Edge.Cuts" user "Board Geometry/Outline")
		(27 "Margin" user)
		(31 "F.CrtYd" user "Package Geometry/Place Bound Top")
		(29 "B.CrtYd" user "Package Geometry/Place Bound Bottom")
		(35 "F.Fab" user "Ref Des/Assembly Top")
		(33 "B.Fab" user "Ref Des/Assembly Bottom")
	)
	(footprint ""
		(layer "F.Cu")
		(at 79.924148 -53.126894 -90)
		(property "Reference" "C386"
			(at 0 0 270)
			(layer "F.SilkS")
			(hide yes)
			(effects
				(font
					(size 1.27 1.27)
				)
			)
		)
		(property "Value" "SCD033U25V2KX-GP"
			(at 1.1811 -2.7051 270)
			(unlocked yes)
			(layer "F.Fab")
			(hide yes)
			(effects
				(font
					(size 1.016 1.016)
					(thickness 0.1524)
				)
			)
		)
		(property "Device Type" "C402H22"
			(at 1.1811 -4.2291 270)
			(unlocked yes)
			(layer "F.Fab")
			(hide yes)
			(effects
				(font
					(size 1.016 1.016)
					(thickness 0.1524)
				)
			)
		)
		(duplicate_pad_numbers_are_jumpers no)
		(fp_rect
			(start -0.4318 0.9525)
			(end 0.4318 -0.9525)
			(stroke
				(width 0)
				(type default)
			)
			(fill no)
			(layer "F.CrtYd")
		)
		(fp_rect
			(start -0.4318 0.9525)
			(end 0.4318 -0.9525)
			(stroke
				(width 0)
				(type default)
			)
			(fill no)
			(layer "F.Fab")
		)
		(pad "1" smd custom
			(at 0 -0.4445 270)
			(size 0.1524 0.1524)
			(layers "F.Cu" "F.Mask" "F.Paste")
			(net "SW_HDD_P26")
			(options
				(clearance outline)
				(anchor circle)
			)
			(primitives
				(gr_poly
					(pts
						(arc
							(start 0.3048 -0.2032)
							(mid 0.275042 -0.275042)
							(end 0.2032 -0.3048)
						)
						(arc
							(start -0.2032 -0.3048)
							(mid -0.275042 -0.275042)
							(end -0.3048 -0.2032)
						)
						(arc
							(start -0.3048 0.2032)
							(mid -0.275042 0.275042)
							(end -0.2032 0.3048)
						)
						(arc
							(start 0.2032 0.3048)
							(mid 0.275042 0.275042)
							(end 0.3048 0.2032)
						)
					)
					(width 0)
					(fill yes)
				)
			)
		)
		(pad "2" smd custom
			(at 0 0.4445 270)
			(size 0.1524 0.1524)
			(layers "F.Cu" "F.Mask" "F.Paste")
			(net "GND")
			(options
				(clearance outline)
				(anchor circle)
			)
			(primitives
				(gr_poly
					(pts
						(arc
							(start 0.3048 -0.2032)
							(mid 0.275042 -0.275042)
							(end 0.2032 -0.3048)
						)
						(arc
							(start -0.2032 -0.3048)
							(mid -0.275042 -0.275042)
							(end -0.3048 -0.2032)
						)
						(arc
							(start -0.3048 0.2032)
							(mid -0.275042 0.275042)
							(end -0.2032 0.3048)
						)
						(arc
							(start 0.2032 0.3048)
							(mid 0.275042 0.275042)
							(end 0.3048 0.2032)
						)
					)
					(width 0)
					(fill yes)
				)
			)
		)
	)
	(footprint ""
		(layer "F.Cu")
		(at 67.206876 -304.385472 180)
		(property "Reference" "R228"
			(at 0 0 180)
			(layer "F.SilkS")
			(hide yes)
			(effects
				(font
					(size 1.27 1.27)
				)
			)
		)
		(property "Value" "130R3F-GP"
			(at -0.0254 -2.5146 180)
			(unlocked yes)
			(layer "F.Fab")
			(hide yes)
			(effects
				(font
					(size 1.016 1.016)
					(thickness 0.1524)
				)
			)
		)
		(property "Device Type" "R603H22"
			(at -0.0254 -4.0386 180)
			(unlocked yes)
			(layer "F.Fab")
			(hide yes)
			(effects
				(font
					(size 1.016 1.016)
					(thickness 0.1524)
				)
			)
		)
		(duplicate_pad_numbers_are_jumpers no)
		(fp_line
			(start 0.2032 0)
			(end 0.4826 0)
			(stroke
				(width 0.2032)
				(type default)
			)
			(layer "F.SilkS")
		)
		(fp_line
			(start -0.4826 0)
			(end -0.2032 0)
			(stroke
				(width 0.2032)
				(type default)
			)
			(layer "F.SilkS")
		)
		(fp_rect
			(start -0.5842 1.3335)
			(end 0.5842 -1.3335)
			(stroke
				(width 0)
				(type default)
			)
			(fill no)
			(layer "F.CrtYd")
		)
		(fp_rect
			(start -0.5842 1.3335)
			(end 0.5842 -1.3335)
			(stroke
				(width 0)
				(type default)
			)
			(fill no)
			(layer "F.Fab")
		)
		(pad "1" smd custom
			(at 0 -0.762 180)
			(size 0.2159 0.2159)
			(layers "F.Cu" "F.Mask" "F.Paste")
			(net "P5V_B")
			(options
				(clearance outline)
				(anchor circle)
			)
			(primitives
				(gr_poly
					(pts
						(arc
							(start -0.3302 -0.4318)
							(mid -0.402042 -0.402042)
							(end -0.4318 -0.3302)
						)
						(arc
							(start -0.4318 0.3302)
							(mid -0.402042 0.402042)
							(end -0.3302 0.4318)
						)
						(arc
							(start 0.3302 0.4318)
							(mid 0.402042 0.402042)
							(end 0.4318 0.3302)
						)
						(arc
							(start 0.4318 -0.3302)
							(mid 0.402042 -0.402042)
							(end 0.3302 -0.4318)
						)
					)
					(width 0)
					(fill yes)
				)
			)
		)
		(pad "2" smd custom
			(at 0 0.762 180)
			(size 0.2159 0.2159)
			(layers "F.Cu" "F.Mask" "F.Paste")
			(net "FLT_HDD26")
			(options
				(clearance outline)
				(anchor circle)
			)
			(primitives
				(gr_poly
					(pts
						(arc
							(start -0.3302 -0.4318)
							(mid -0.402042 -0.402042)
							(end -0.4318 -0.3302)
						)
						(arc
							(start -0.4318 0.3302)
							(mid -0.402042 0.402042)
							(end -0.3302 0.4318)
						)
						(arc
							(start 0.3302 0.4318)
							(mid 0.402042 0.402042)
							(end 0.4318 0.3302)
						)
						(arc
							(start 0.4318 -0.3302)
							(mid 0.402042 -0.402042)
							(end 0.3302 -0.4318)
						)
					)
					(width 0)
					(fill yes)
				)
			)
		)
	)
	(footprint ""
		(layer "F.Cu")
		(at 22.970998 -161.014918 -90)
		(property "Reference" "R414"
			(at 0 0 270)
			(layer "F.SilkS")
			(hide yes)
			(effects
				(font
					(size 1.27 1.27)
				)
			)
		)
		(property "Value" "1KR2F-3-GP"
			(at 0.064008 -3.993896 270)
			(unlocked yes)
			(layer "F.Fab")
			(hide yes)
			(effects
				(font
					(size 1.016 1.016)
					(thickness 0.1524)
				)
			)
		)
		(property "Device Type" "R402H16"
			(at 0.064008 -5.517896 270)
			(unlocked yes)
			(layer "F.Fab")
			(hide yes)
			(effects
				(font
					(size 1.016 1.016)
					(thickness 0.1524)
				)
			)
		)
		(duplicate_pad_numbers_are_jumpers no)
		(fp_line
			(start -0.508 -0.9398)
			(end -0.508 0.9398)
			(stroke
				(width 0.1524)
				(type default)
			)
			(layer "F.SilkS")
		)
		(fp_line
			(start 0.508 -0.9398)
			(end -0.508 -0.9398)
			(stroke
				(width 0.1524)
				(type default)
			)
			(layer "F.SilkS")
		)
		(fp_rect
			(start -0.508 0.9398)
			(end 0.508 -0.9398)
			(stroke
				(width 0)
				(type default)
			)
			(fill no)
			(layer "F.CrtYd")
		)
		(fp_rect
			(start -0.508 0.9398)
			(end 0.508 -0.9398)
			(stroke
				(width 0)
				(type default)
			)
			(fill no)
			(layer "F.Fab")
		)
		(pad "1" smd custom
			(at 0 -0.4445 270)
			(size 0.1397 0.1397)
			(layers "F.Cu" "F.Mask" "F.Paste")
			(net "P3V3_STBY_A")
			(options
				(clearance outline)
				(anchor circle)
			)
			(primitives
				(gr_poly
					(pts
						(arc
							(start -0.1778 -0.2794)
							(mid -0.249642 -0.249642)
							(end -0.2794 -0.1778)
						)
						(arc
							(start -0.2794 0.1778)
							(mid -0.249642 0.249642)
							(end -0.1778 0.2794)
						)
						(arc
							(start 0.1778 0.2794)
							(mid 0.249642 0.249642)
							(end 0.2794 0.1778)
						)
						(arc
							(start 0.2794 -0.1778)
							(mid 0.249642 -0.249642)
							(end 0.1778 -0.2794)
						)
					)
					(width 0)
					(fill yes)
				)
			)
		)
		(pad "2" smd custom
			(at 0 0.4445 270)
			(size 0.1397 0.1397)
			(layers "F.Cu" "F.Mask" "F.Paste")
			(net "SW_PWR_R_HDD12")
			(options
				(clearance outline)
				(anchor circle)
			)
			(primitives
				(gr_poly
					(pts
						(arc
							(start -0.1778 -0.2794)
							(mid -0.249642 -0.249642)
							(end -0.2794 -0.1778)
						)
						(arc
							(start -0.2794 0.1778)
							(mid -0.249642 0.249642)
							(end -0.1778 0.2794)
						)
						(arc
							(start 0.1778 0.2794)
							(mid 0.249642 0.249642)
							(end 0.2794 0.1778)
						)
						(arc
							(start 0.2794 -0.1778)
							(mid 0.249642 -0.249642)
							(end 0.1778 -0.2794)
						)
					)
					(width 0)
					(fill yes)
				)
			)
		)
	)
	(footprint ""
		(layer "F.Cu")
		(at 427.390052 -48.554894 -90)
		(property "Reference" "R896"
			(at 0 0 270)
			(layer "F.SilkS")
			(hide yes)
			(effects
				(font
					(size 1.27 1.27)
				)
			)
		)
		(property "Value" "4K7R2J-2-GP"
			(at 0.064008 -3.993896 270)
			(unlocked yes)
			(layer "F.Fab")
			(hide yes)
			(effects
				(font
					(size 1.016 1.016)
					(thickness 0.1524)
				)
			)
		)
		(property "Device Type" "R402H16"
			(at 0.064008 -5.517896 270)
			(unlocked yes)
			(layer "F.Fab")
			(hide yes)
			(effects
				(font
					(size 1.016 1.016)
					(thickness 0.1524)
				)
			)
		)
		(duplicate_pad_numbers_are_jumpers no)
		(fp_line
			(start -0.508 -0.9398)
			(end -0.508 0.9398)
			(stroke
				(width 0.1524)
				(type default)
			)
			(layer "F.SilkS")
		)
		(fp_line
			(start 0.508 -0.9398)
			(end -0.508 -0.9398)
			(stroke
				(width 0.1524)
				(type default)
			)
			(layer "F.SilkS")
		)
		(fp_rect
			(start -0.508 0.9398)
			(end 0.508 -0.9398)
			(stroke
				(width 0)
				(type default)
			)
			(fill no)
			(layer "F.CrtYd")
		)
		(fp_rect
			(start -0.508 0.9398)
			(end 0.508 -0.9398)
			(stroke
				(width 0)
				(type default)
			)
			(fill no)
			(layer "F.Fab")
		)
		(pad "1" smd custom
			(at 0 -0.4445 270)
			(size 0.1397 0.1397)
			(layers "F.Cu" "F.Mask" "F.Paste")
			(net "P12V_A")
			(options
				(clearance outline)
				(anchor circle)
			)
			(primitives
				(gr_poly
					(pts
						(arc
							(start -0.1778 -0.2794)
							(mid -0.249642 -0.249642)
							(end -0.2794 -0.1778)
						)
						(arc
							(start -0.2794 0.1778)
							(mid -0.249642 0.249642)
							(end -0.1778 0.2794)
						)
						(arc
							(start 0.1778 0.2794)
							(mid 0.249642 0.249642)
							(end 0.2794 0.1778)
						)
						(arc
							(start 0.2794 -0.1778)
							(mid 0.249642 -0.249642)
							(end 0.1778 -0.2794)
						)
					)
					(width 0)
					(fill yes)
				)
			)
		)
		(pad "2" smd custom
			(at 0 0.4445 270)
			(size 0.1397 0.1397)
			(layers "F.Cu" "F.Mask" "F.Paste")
			(net "SW_HDD_P33")
			(options
				(clearance outline)
				(anchor circle)
			)
			(primitives
				(gr_poly
					(pts
						(arc
							(start -0.1778 -0.2794)
							(mid -0.249642 -0.249642)
							(end -0.2794 -0.1778)
						)
						(arc
							(start -0.2794 0.1778)
							(mid -0.249642 0.249642)
							(end -0.1778 0.2794)
						)
						(arc
							(start 0.1778 0.2794)
							(mid 0.249642 0.249642)
							(end 0.2794 0.1778)
						)
						(arc
							(start 0.2794 -0.1778)
							(mid 0.249642 -0.249642)
							(end 0.1778 -0.2794)
						)
					)
					(width 0)
					(fill yes)
				)
			)
		)
	)
	(footprint ""
		(layer "F.Cu")
		(at 259.6896 -284.4292 180)
		(property "Reference" "R106"
			(at 0 0 180)
			(layer "F.SilkS")
			(hide yes)
			(effects
				(font
					(size 1.27 1.27)
				)
			)
		)
		(property "Value" "0R2J-2-GP"
			(at 0.064008 -3.993896 180)
			(unlocked yes)
			(layer "F.Fab")
			(hide yes)
			(effects
				(font
					(size 1.016 1.016)
					(thickness 0.1524)
				)
			)
		)
		(property "Device Type" "R402H16"
			(at 0.064008 -5.517896 180)
			(unlocked yes)
			(layer "F.Fab")
			(hide yes)
			(effects
				(font
					(size 1.016 1.016)
					(thickness 0.1524)
				)
			)
		)
		(duplicate_pad_numbers_are_jumpers no)
		(fp_line
			(start 0.508 -0.9398)
			(end -0.508 -0.9398)
			(stroke
				(width 0.1524)
				(type default)
			)
			(layer "F.SilkS")
		)
		(fp_line
			(start -0.508 -0.9398)
			(end -0.508 0.9398)
			(stroke
				(width 0.1524)
				(type default)
			)
			(layer "F.SilkS")
		)
		(fp_rect
			(start -0.508 0.9398)
			(end 0.508 -0.9398)
			(stroke
				(width 0)
				(type default)
			)
			(fill no)
			(layer "F.CrtYd")
		)
		(fp_rect
			(start -0.508 0.9398)
			(end 0.508 -0.9398)
			(stroke
				(width 0)
				(type default)
			)
			(fill no)
			(layer "F.Fab")
		)
		(pad "1" smd custom
			(at 0 -0.4445 180)
			(size 0.1397 0.1397)
			(layers "F.Cu" "F.Mask" "F.Paste")
			(net "IO_EXP0_LED_SDA")
			(options
				(clearance outline)
				(anchor circle)
			)
			(primitives
				(gr_poly
					(pts
						(arc
							(start -0.1778 -0.2794)
							(mid -0.249642 -0.249642)
							(end -0.2794 -0.1778)
						)
						(arc
							(start -0.2794 0.1778)
							(mid -0.249642 0.249642)
							(end -0.1778 0.2794)
						)
						(arc
							(start 0.1778 0.2794)
							(mid 0.249642 0.249642)
							(end 0.2794 0.1778)
						)
						(arc
							(start 0.2794 -0.1778)
							(mid 0.249642 -0.249642)
							(end 0.1778 -0.2794)
						)
					)
					(width 0)
					(fill yes)
				)
			)
		)
		(pad "2" smd custom
			(at 0 0.4445 180)
			(size 0.1397 0.1397)
			(layers "F.Cu" "F.Mask" "F.Paste")
			(net "I2C_DRIVE_A_FLT_LED_SDA")
			(options
				(clearance outline)
				(anchor circle)
			)
			(primitives
				(gr_poly
					(pts
						(arc
							(start -0.1778 -0.2794)
							(mid -0.249642 -0.249642)
							(end -0.2794 -0.1778)
						)
						(arc
							(start -0.2794 0.1778)
							(mid -0.249642 0.249642)
							(end -0.1778 0.2794)
						)
						(arc
							(start 0.1778 0.2794)
							(mid 0.249642 0.249642)
							(end 0.2794 0.1778)
						)
						(arc
							(start 0.2794 -0.1778)
							(mid 0.249642 -0.249642)
							(end 0.1778 -0.2794)
						)
					)
					(width 0)
					(fill yes)
				)
			)
		)
	)
	(footprint ""
		(layer "F.Cu")
		(at 415.579052 -295.064942 -90)
		(property "Reference" "R341"
			(at 0 0 270)
			(layer "F.SilkS")
			(hide yes)
			(effects
				(font
					(size 1.27 1.27)
				)
			)
		)
		(property "Value" "220R3F-1-GP"
			(at -0.0254 -2.5146 270)
			(unlocked yes)
			(layer "F.Fab")
			(hide yes)
			(effects
				(font
					(size 1.016 1.016)
					(thickness 0.1524)
				)
			)
		)
		(property "Device Type" "R603H22"
			(at -0.0254 -4.0386 270)
			(unlocked yes)
			(layer "F.Fab")
			(hide yes)
			(effects
				(font
					(size 1.016 1.016)
					(thickness 0.1524)
				)
			)
		)
		(duplicate_pad_numbers_are_jumpers no)
		(fp_line
			(start -0.4826 0)
			(end -0.2032 0)
			(stroke
				(width 0.2032)
				(type default)
			)
			(layer "F.SilkS")
		)
		(fp_line
			(start 0.2032 0)
			(end 0.4826 0)
			(stroke
				(width 0.2032)
				(type default)
			)
			(layer "F.SilkS")
		)
		(fp_rect
			(start -0.5842 1.3335)
			(end 0.5842 -1.3335)
			(stroke
				(width 0)
				(type default)
			)
			(fill no)
			(layer "F.CrtYd")
		)
		(fp_rect
			(start -0.5842 1.3335)
			(end 0.5842 -1.3335)
			(stroke
				(width 0)
				(type default)
			)
			(fill no)
			(layer "F.Fab")
		)
		(pad "1" smd custom
			(at 0 -0.762 270)
			(size 0.2159 0.2159)
			(layers "F.Cu" "F.Mask" "F.Paste")
			(net "HDD_PRSNT_9")
			(options
				(clearance outline)
				(anchor circle)
			)
			(primitives
				(gr_poly
					(pts
						(arc
							(start -0.3302 -0.4318)
							(mid -0.402042 -0.402042)
							(end -0.4318 -0.3302)
						)
						(arc
							(start -0.4318 0.3302)
							(mid -0.402042 0.402042)
							(end -0.3302 0.4318)
						)
						(arc
							(start 0.3302 0.4318)
							(mid 0.402042 0.402042)
							(end 0.4318 0.3302)
						)
						(arc
							(start 0.4318 -0.3302)
							(mid 0.402042 -0.402042)
							(end 0.3302 -0.4318)
						)
					)
					(width 0)
					(fill yes)
				)
			)
		)
		(pad "2" smd custom
			(at 0 0.762 270)
			(size 0.2159 0.2159)
			(layers "F.Cu" "F.Mask" "F.Paste")
			(net "DRIVE_A_9_INS")
			(options
				(clearance outline)
				(anchor circle)
			)
			(primitives
				(gr_poly
					(pts
						(arc
							(start -0.3302 -0.4318)
							(mid -0.402042 -0.402042)
							(end -0.4318 -0.3302)
						)
						(arc
							(start -0.4318 0.3302)
							(mid -0.402042 0.402042)
							(end -0.3302 0.4318)
						)
						(arc
							(start 0.3302 0.4318)
							(mid 0.402042 0.402042)
							(end 0.4318 0.3302)
						)
						(arc
							(start 0.4318 -0.3302)
							(mid 0.402042 -0.402042)
							(end 0.3302 -0.4318)
						)
					)
					(width 0)
					(fill yes)
				)
			)
		)
	)
	(footprint ""
		(layer "F.Cu")
		(at 272.542 -328.905108 180)
		(property "Reference" "VIA55"
			(at 0 0 180)
			(layer "F.SilkS")
			(hide yes)
			(effects
				(font
					(size 1.27 1.27)
				)
			)
		)
		(property "Value" "100OHM-8L-1D6MM-L18L16-GP"
			(at -3.7211 -4.5085 180)
			(unlocked yes)
			(layer "F.Fab")
			(hide yes)
			(effects
				(font
					(size 1.016 1.016)
					(thickness 0.1524)
				)
			)
		)
		(property "Device Type" "VIA-PCIE-4P-394076"
			(at -3.7211 -6.0325 180)
			(unlocked yes)
			(layer "F.Fab")
			(hide yes)
			(effects
				(font
					(size 1.016 1.016)
					(thickness 0.1524)
				)
			)
		)
		(duplicate_pad_numbers_are_jumpers no)
		(fp_rect
			(start -1.9685 0.381)
			(end 1.9685 -0.381)
			(stroke
				(width 0)
				(type default)
			)
			(fill no)
			(layer "F.CrtYd")
		)
		(fp_rect
			(start -1.9685 0.381)
			(end 1.9685 -0.381)
			(stroke
				(width 0)
				(type default)
			)
			(fill no)
			(layer "F.Fab")
		)
		(pad "1" thru_hole circle
			(at -1.5875 0 180)
			(size 0.508 0.508)
			(drill 0.254)
			(layers "*.Cu" "*.Mask")
			(remove_unused_layers no)
			(net "GND")
			(clearance 0.127)
			(thermal_gap 0.127)
		)
		(pad "2" thru_hole circle
			(at -0.5715 0 180)
			(size 0.508 0.508)
			(drill 0.254)
			(layers "*.Cu" "*.Mask")
			(remove_unused_layers no)
			(net "PHY_SCC_A_TO_DRV_A_17_DP")
			(clearance 0.127)
			(thermal_gap 0.127)
		)
		(pad "3" thru_hole circle
			(at 0.5715 0 180)
			(size 0.508 0.508)
			(drill 0.254)
			(layers "*.Cu" "*.Mask")
			(remove_unused_layers no)
			(net "PHY_SCC_A_TO_DRV_A_17_DN")
			(clearance 0.127)
			(thermal_gap 0.127)
		)
		(pad "4" thru_hole circle
			(at 1.5875 0 180)
			(size 0.508 0.508)
			(drill 0.254)
			(layers "*.Cu" "*.Mask")
			(remove_unused_layers no)
			(net "GND")
			(clearance 0.127)
			(thermal_gap 0.127)
		)
	)
)
